# SCM (Grand Teton) — schematic netlist excerpt (pin names and nets, part order shuffled) for the footprints in the layout excerpt that follows; sources: Cadence DE-HDL packaged netlist, KiCad conversion of 12092022_DA0F0TMDCD0_F0T_Management_Board_D_brd_V3_OCP.brd

R272  Q_RES  0 5% CHIP  pkg 0402LF  page 34 : A = SMB_BMC_MM16_R3_SCL ; B = SMB_BMC_MM16_R5_SCL
C125  Q_CAP  22UF 6.3V 20% X6S  pkg C0603  page 16 : A = P3V3_AUX ; B = GND

(kicad_pcb
	(version 20260206)
	(generator "pcbnew")
	(generator_version "10.0")
	(general
		(thickness 1.6)
		(legacy_teardrops no)
	)
	(paper "A4")
	(title_block
		(title "12092022_DA0F0TMDCD0_F0T_Management_Board_D_brd_V3_OCP.brd")
		(comment 1 "Grand Teton / footprints 1241-1242 of 1440")
	)
	(layers
		(0 "F.Cu" signal "TOP")
		(4 "In1.Cu" signal "GND")
		(6 "In2.Cu" signal "IN1")
		(8 "In3.Cu" signal "GND1")
		(10 "In4.Cu" signal "IN2")
		(12 "In5.Cu" signal "VCC")
		(14 "In6.Cu" signal "VCC1")
		(16 "In7.Cu" signal "IN3")
		(18 "In8.Cu" signal "GND2")
		(20 "In9.Cu" signal "IN4")
		(22 "In10.Cu" signal "GND3")
		(2 "B.Cu" signal "BOTTOM")
		(9 "F.Adhes" user "F.Adhesive")
		(11 "B.Adhes" user "B.Adhesive")
		(13 "F.Paste" user "Package Geometry/Pastemask Top")
		(15 "B.Paste" user "Package Geometry/Pastemask Bottom")
		(5 "F.SilkS" user "Ref Des/Silkscreen Top")
		(7 "B.SilkS" user "Ref Des/Silkscreen Bottom")
		(1 "F.Mask" user "Board Geometry/Soldermask Top")
		(3 "B.Mask" user "Board Geometry/Soldermask Bottom")
		(17 "Dwgs.User" user "User.Drawings")
		(19 "Cmts.User" user "User.Comments")
		(21 "Eco1.User" user "User.Eco1")
		(23 "Eco2.User" user "User.Eco2")
		(25 "Edge.Cuts" user "Board Geometry/Outline")
		(27 "Margin" user)
		(31 "F.CrtYd" user "Package Geometry/Place Bound Top")
		(29 "B.CrtYd" user "Package Geometry/Place Bound Bottom")
		(35 "F.Fab" user "Ref Des/Assembly Top")
		(33 "B.Fab" user "Ref Des/Assembly Bottom")
	)
	(footprint ""
		(layer "B.Cu")
		(at 17.272 -80.772 90)
		(property "Reference" "R272"
			(at 0 0 90)
			(layer "B.SilkS")
			(hide yes)
			(effects
				(font
					(size 1.27 1.27)
				)
				(justify mirror)
			)
		)
		(property "Value" ""
			(at 0 0 90)
			(layer "B.Fab")
			(effects
				(font
					(size 1.27 1.27)
				)
				(justify mirror)
			)
		)
		(duplicate_pad_numbers_are_jumpers no)
		(fp_line
			(start 0.7874 -0.4064)
			(end -0.7874 -0.4064)
			(stroke
				(width 0.1524)
				(type default)
			)
			(layer "B.SilkS")
		)
		(fp_line
			(start -0.7874 -0.4064)
			(end -0.7874 0.4064)
			(stroke
				(width 0.1524)
				(type default)
			)
			(layer "B.SilkS")
		)
		(fp_line
			(start 0.7874 0.4064)
			(end 0.7874 -0.4064)
			(stroke
				(width 0.1524)
				(type default)
			)
			(layer "B.SilkS")
		)
		(fp_line
			(start -0.7874 0.4064)
			(end 0.7874 0.4064)
			(stroke
				(width 0.1524)
				(type default)
			)
			(layer "B.SilkS")
		)
		(fp_line
			(start 0.67945 -0.305054)
			(end 0.12065 -0.305054)
			(stroke
				(width 0.1)
				(type default)
			)
			(layer "B.Fab")
		)
		(fp_line
			(start 0.12065 -0.305054)
			(end 0.12065 -0.2794)
			(stroke
				(width 0.1)
				(type default)
			)
			(layer "B.Fab")
		)
		(fp_line
			(start -0.12065 -0.3048)
			(end -0.67945 -0.3048)
			(stroke
				(width 0.1)
				(type default)
			)
			(layer "B.Fab")
		)
		(fp_line
			(start -0.67945 -0.3048)
			(end -0.67945 0.3048)
			(stroke
				(width 0.1)
				(type default)
			)
			(layer "B.Fab")
		)
		(fp_line
			(start 0.12065 -0.2794)
			(end -0.12065 -0.2794)
			(stroke
				(width 0.1)
				(type default)
			)
			(layer "B.Fab")
		)
		(fp_line
			(start -0.12065 -0.2794)
			(end -0.12065 -0.3048)
			(stroke
				(width 0.1)
				(type default)
			)
			(layer "B.Fab")
		)
		(fp_line
			(start 0.12065 0.2794)
			(end 0.12065 0.3048)
			(stroke
				(width 0.1)
				(type default)
			)
			(layer "B.Fab")
		)
		(fp_line
			(start -0.120396 0.2794)
			(end 0.12065 0.2794)
			(stroke
				(width 0.1)
				(type default)
			)
			(layer "B.Fab")
		)
		(fp_line
			(start 0.67945 0.3048)
			(end 0.67945 -0.305054)
			(stroke
				(width 0.1)
				(type default)
			)
			(layer "B.Fab")
		)
		(fp_line
			(start 0.12065 0.3048)
			(end 0.67945 0.3048)
			(stroke
				(width 0.1)
				(type default)
			)
			(layer "B.Fab")
		)
		(fp_line
			(start -0.120396 0.3048)
			(end -0.120396 0.2794)
			(stroke
				(width 0.1)
				(type default)
			)
			(layer "B.Fab")
		)
		(fp_line
			(start -0.67945 0.3048)
			(end -0.120396 0.3048)
			(stroke
				(width 0.1)
				(type default)
			)
			(layer "B.Fab")
		)
		(pad "1" smd circle
			(at 0.40005 0 270)
			(size 0 0)
			(layers "B.Cu" "B.Mask" "B.Paste")
			(net "SMB_BMC_MM16_R3_SCL")
		)
		(pad "2" smd circle
			(at -0.40005 0 270)
			(size 0 0)
			(layers "B.Cu" "B.Mask" "B.Paste")
			(net "SMB_BMC_MM16_R5_SCL")
		)
	)
	(footprint ""
		(layer "B.Cu")
		(at 83.8454 -30.5435 180)
		(property "Reference" "C125"
			(at 0 0 0)
			(layer "B.SilkS")
			(hide yes)
			(effects
				(font
					(size 1.27 1.27)
				)
				(justify mirror)
			)
		)
		(property "Value" ""
			(at 0 0 0)
			(layer "B.Fab")
			(effects
				(font
					(size 1.27 1.27)
				)
				(justify mirror)
			)
		)
		(duplicate_pad_numbers_are_jumpers no)
		(fp_line
			(start 1.2954 0.5842)
			(end 1.2954 -0.5842)
			(stroke
				(width 0.1524)
				(type default)
			)
			(layer "B.SilkS")
		)
		(fp_line
			(start 1.2954 -0.5842)
			(end -1.2954 -0.5842)
			(stroke
				(width 0.1524)
				(type default)
			)
			(layer "B.SilkS")
		)
		(fp_line
			(start 0 -0.5842)
			(end 0 0.5842)
			(stroke
				(width 0.1524)
				(type default)
			)
			(layer "B.SilkS")
		)
		(fp_line
			(start -1.2954 0.5842)
			(end 1.2954 0.5842)
			(stroke
				(width 0.1524)
				(type default)
			)
			(layer "B.SilkS")
		)
		(fp_line
			(start -1.2954 -0.5842)
			(end -1.2954 0.5842)
			(stroke
				(width 0.1524)
				(type default)
			)
			(layer "B.SilkS")
		)
		(fp_line
			(start 1.1938 0.4064)
			(end 1.1938 -0.4064)
			(stroke
				(width 0.1)
				(type default)
			)
			(layer "B.Fab")
		)
		(fp_line
			(start 1.1938 -0.4064)
			(end 0.8636 -0.4064)
			(stroke
				(width 0.1)
				(type default)
			)
			(layer "B.Fab")
		)
		(fp_line
			(start 0.8636 0.4572)
			(end 0.8636 0.4064)
			(stroke
				(width 0.1)
				(type default)
			)
			(layer "B.Fab")
		)
		(fp_line
			(start 0.8636 0.4064)
			(end 1.1938 0.4064)
			(stroke
				(width 0.1)
				(type default)
			)
			(layer "B.Fab")
		)
		(fp_line
			(start 0.8636 -0.4064)
			(end 0.8636 -0.4572)
			(stroke
				(width 0.1)
				(type default)
			)
			(layer "B.Fab")
		)
		(fp_line
			(start 0.8636 -0.4572)
			(end -0.8636 -0.4572)
			(stroke
				(width 0.1)
				(type default)
			)
			(layer "B.Fab")
		)
		(fp_line
			(start -0.8636 0.4572)
			(end 0.8636 0.4572)
			(stroke
				(width 0.1)
				(type default)
			)
			(layer "B.Fab")
		)
		(fp_line
			(start -0.8636 0.4064)
			(end -0.8636 0.4572)
			(stroke
				(width 0.1)
				(type default)
			)
			(layer "B.Fab")
		)
		(fp_line
			(start -0.8636 -0.4064)
			(end -1.1938 -0.4064)
			(stroke
				(width 0.1)
				(type default)
			)
			(layer "B.Fab")
		)
		(fp_line
			(start -0.8636 -0.4572)
			(end -0.8636 -0.4064)
			(stroke
				(width 0.1)
				(type default)
			)
			(layer "B.Fab")
		)
		(fp_line
			(start -1.1938 0.4064)
			(end -0.8636 0.4064)
			(stroke
				(width 0.1)
				(type default)
			)
			(layer "B.Fab")
		)
		(fp_line
			(start -1.1938 -0.4064)
			(end -1.1938 0.4064)
			(stroke
				(width 0.1)
				(type default)
			)
			(layer "B.Fab")
		)
		(pad "1" smd rect
			(at 0.7366 0 90)
			(size 0.7112 0.8128)
			(layers "B.Cu" "B.Mask" "B.Paste")
			(net "P3V3_AUX")
		)
		(pad "2" smd rect
			(at -0.7366 0 90)
			(size 0.7112 0.8128)
			(layers "B.Cu" "B.Mask" "B.Paste")
			(net "GND")
		)
	)
)
